FILE_TYPE = CONNECTIVITY;
{Allegro Design Entry HDL 16.6-p007 (v16-6-112F) 10/10/2012}
"PAGE_NUMBER" = 184;
0"NC";
1"GND\g";
2"GND\g";
3"P3V3_STBY\g";
4"SPI_PCH_TPM_CS_N";
5"SPI_PCH_MISO";
6"SMB_SENSOR_STBY_LVC3_SCL";
7"IRQ_SPI_TPM_N_R";
8"FM_TPM_PRES_RST_N";
9"IRQ_PIRQA_SPI_TPM_N";
10"SPI_PCH_MOSI";
11"SPI_PCH_CLK";
12"SPI_PCH_TPM_MISO_R";
13"SPI_PCH_TPM_CLK_R";
14"SPI_PCH_TPM_MOSI_R";
15"SPI_PCH_TPM_CS_R_N";
16"RST_PLTRST_BUF_N";
17"SMB_SENSOR_STBY_LVC3_SDA";
%"GND"
"1","(-3225,-3900)","2","mstr_symbols","I101";
;
HDL_POWER"GND"
BODY_TYPE"PLUMBING"
ROOM"DDR4_CH_G"
CDS_LIB"mstr_symbols"
SIZE"1B"
BOM_COST"MEM"
VOLTAGE"0";
"A\NAC"1;
%"STANDOFF"
"2","(-5125,-1900)","0","mstr_misc","I104";
;
CDS_SEC"1"
CDS_LIB"mstr_misc"
SEC_TYPE"TH1"
SEC"1"
CDS_LOCATION"RM8D1"
PACK_TYPE"TH1"
MATERIAL"SO"
PART_NUMBER"H72821-001"
LOCATION"RM8D1";
"IO1"
$PN"1"2;
%"GND"
"1","(-4850,-2125)","0","mstr_symbols","I105";
;
HDL_POWER"GND"
BODY_TYPE"PLUMBING"
CDS_LIB"mstr_symbols"
SIZE"1B"
VOLTAGE"0.0V";
"A\NAC"2;
%"SCONN11_H67026001"
"1","(-3700,-3375)","0","mstr_sconn","I87";
;
CDS_SEC"1"
ROOM"TPM"
BOM_COST"MIO_SECURITY"
CDS_LMAN_SYM_OUTLINE"-300,450,300,-450"
CDS_LIB"mstr_sconn"
SEC_TYPE"SM"
SEC"1"
CDS_LOCATION"J8E1"
PACK_TYPE"SM"
MATERIAL"CONN"
PART_NUMBER"H67026-001"
LOCATION"J8E1";
"IO7"
$PN"7"3;
"IO8"
$PN"8"8;
"IO5"
$PN"5"15;
"IO6"
$PN"6"17;
"IO4"
$PN"4"12;
"IO3"
$PN"3"14;
"IO2"
$PN"2"16;
"IO1"
$PN"1"13;
"MP1"
$PN"MP1"1;
"IO9"
$PN"9"7;
"IO10"
$PN"10"6;
"IO11"
$PN"11"1;
"MP2"
$PN"MP2"1;
%"RES"
"1","(-4750,-3175)","0","mstr_discrete","I88";
;
CDS_SEC"1"
ROOM"TPM"
SEC_TYPE"0402"
CDS_LIB"mstr_discrete"
BOM_COST"MIO_SECURITY"
SEC"1"
CDS_LOCATION"R8E9"
MATERIAL"CHIP"
WATTAGE"1/16W"
PACK_TYPE"0402"
TOLERANCE"1%"
VALUE"33.2"
PART_NUMBER"G21796-074"
LOCATION"R8E9";
"B"
$PN"2"13;
"A"
$PN"1"11;
%"RES"
"1","(-4750,-3575)","0","mstr_discrete","I92";
;
CDS_SEC"1"
ROOM"TPM"
BOM_COST"MIO_SECURITY"
CDS_LIB"mstr_discrete"
SEC_TYPE"0402"
SEC"1"
CDS_LOCATION"R8D35"
PART_NUMBER"G21497-005"
WATTAGE"1/16W"
MATERIAL"CHIP"
PACK_TYPE"0402"
TOLERANCE"5%"
VALUE"0.0"
LOCATION"R8D35";
"B"
$PN"2"15;
"A"
$PN"1"4;
%"RES"
"1","(-4725,-3475)","0","mstr_discrete","I93";
;
CDS_SEC"1"
ROOM"TPM"
SEC_TYPE"0402"
BOM_COST"MIO_SECURITY"
CDS_LIB"mstr_discrete"
SEC"1"
CDS_LOCATION"R8E13"
PART_NUMBER"G21796-074"
WATTAGE"1/16W"
MATERIAL"CHIP"
PACK_TYPE"0402"
TOLERANCE"1%"
VALUE"33.2"
LOCATION"R8E13";
"B"
$PN"2"12;
"A"
$PN"1"5;
%"RES"
"1","(-4725,-3375)","0","mstr_discrete","I95";
;
CDS_SEC"1"
ROOM"TPM"
SEC_TYPE"0402"
CDS_LIB"mstr_discrete"
BOM_COST"MIO_SECURITY"
SEC"1"
CDS_LOCATION"R8E10"
PART_NUMBER"G21796-074"
WATTAGE"1/16W"
MATERIAL"CHIP"
PACK_TYPE"0402"
TOLERANCE"1%"
VALUE"33.2"
LOCATION"R8E10";
"B"
$PN"2"14;
"A"
$PN"1"10;
%"P3V3_STBY"
"1","(-3050,-2900)","0","mstr_symbols","I97";
;
HDL_POWER"P3V3_STBY"
BODY_TYPE"PLUMBING"
CDS_LIB"mstr_symbols"
SIZE"1B"
VOLTAGE"3.3V";
"G\NAC"3;
%"RES"
"1","(-2575,-3425)","0","mstr_discrete","I99";
;
ROOM"TPM"
CDS_LIB"mstr_discrete"
BOM_COST"MIO_SECURITY"
CDS_SEC"1"
$SEC"1"
CDS_LOCATION"R8E1"
PART_NUMBER"G21497-005"
VALUE"0.0"
PACK_TYPE"0402"
WATTAGE"1/16W"
TOLERANCE"5%"
MATERIAL"CHIP"
LOCATION"R8E1";
"B"
$PN"2"9;
"A"
$PN"1"7;
END.
